(kicad_pcb
	(version 20260206)
	(generator "pcbnew")
	(generator_version "10.0")
	(general
		(thickness 1.6)
		(legacy_teardrops no)
	)
	(paper "A4")
	(title_block
		(title "baseboard — 13948-1b.1110WZS1818.brd")
		(comment 1 "Honey Badger (Wiwynn) / footprints 1495-1502 of 2523")
	)
	(layers
		(0 "F.Cu" signal "TOP")
		(4 "In1.Cu" signal "L2GND")
		(6 "In2.Cu" signal "L3")
		(8 "In3.Cu" signal "L4VCC")
		(10 "In4.Cu" signal "L5VCC")
		(12 "In5.Cu" signal "L6")
		(14 "In6.Cu" signal "L7GND")
		(2 "B.Cu" signal "BOTTOM")
		(9 "F.Adhes" user "F.Adhesive")
		(11 "B.Adhes" user "B.Adhesive")
		(13 "F.Paste" user "Package Geometry/Pastemask Top")
		(15 "B.Paste" user "Package Geometry/Pastemask Bottom")
		(5 "F.SilkS" user "Ref Des/Silkscreen Top")
		(7 "B.SilkS" user "Ref Des/Silkscreen Bottom")
		(1 "F.Mask" user "Board Geometry/Soldermask Top")
		(3 "B.Mask" user "Board Geometry/Soldermask Bottom")
		(17 "Dwgs.User" user "User.Drawings")
		(19 "Cmts.User" user "User.Comments")
		(21 "Eco1.User" user "User.Eco1")
		(23 "Eco2.User" user "User.Eco2")
		(25 "Edge.Cuts" user "Board Geometry/Outline")
		(27 "Margin" user)
		(31 "F.CrtYd" user "Package Geometry/Place Bound Top")
		(29 "B.CrtYd" user "Package Geometry/Place Bound Bottom")
		(35 "F.Fab" user "Ref Des/Assembly Top")
		(33 "B.Fab" user "Ref Des/Assembly Bottom")
	)
	(footprint ""
		(layer "F.Cu")
		(at 187.442856 -141.868652 -90)
		(property "Reference" "R608"
			(at 0 0 270)
			(layer "F.SilkS")
			(hide yes)
			(effects
				(font
					(size 1.27 1.27)
				)
			)
		)
		(property "Value" "0R2J-2-GP"
			(at 0.064008 -3.993896 270)
			(unlocked yes)
			(layer "F.Fab")
			(hide yes)
			(effects
				(font
					(size 1.016 1.016)
					(thickness 0.1524)
				)
			)
		)
		(property "Device Type" "R402H16"
			(at 0.064008 -5.517896 270)
			(unlocked yes)
			(layer "F.Fab")
			(hide yes)
			(effects
				(font
					(size 1.016 1.016)
					(thickness 0.1524)
				)
			)
		)
		(duplicate_pad_numbers_are_jumpers no)
		(fp_line
			(start -0.508 -0.9398)
			(end -0.508 0.9398)
			(stroke
				(width 0.1524)
				(type default)
			)
			(layer "F.SilkS")
		)
		(fp_line
			(start 0.508 -0.9398)
			(end -0.508 -0.9398)
			(stroke
				(width 0.1524)
				(type default)
			)
			(layer "F.SilkS")
		)
		(fp_rect
			(start -0.508 0.9398)
			(end 0.508 -0.9398)
			(stroke
				(width 0)
				(type default)
			)
			(fill no)
			(layer "F.CrtYd")
		)
		(fp_rect
			(start -0.508 0.9398)
			(end 0.508 -0.9398)
			(stroke
				(width 0)
				(type default)
			)
			(fill no)
			(layer "F.Fab")
		)
		(pad "1" smd custom
			(at 0 -0.4445 270)
			(size 0.1397 0.1397)
			(layers "F.Cu" "F.Mask" "F.Paste")
			(net "EXP_EEPROM_SCL")
			(options
				(clearance outline)
				(anchor circle)
			)
			(primitives
				(gr_poly
					(pts
						(arc
							(start -0.1778 -0.2794)
							(mid -0.249642 -0.249642)
							(end -0.2794 -0.1778)
						)
						(arc
							(start -0.2794 0.1778)
							(mid -0.249642 0.249642)
							(end -0.1778 0.2794)
						)
						(arc
							(start 0.1778 0.2794)
							(mid 0.249642 0.249642)
							(end 0.2794 0.1778)
						)
						(arc
							(start 0.2794 -0.1778)
							(mid 0.249642 -0.249642)
							(end 0.1778 -0.2794)
						)
					)
					(width 0)
					(fill yes)
				)
			)
		)
		(pad "2" smd custom
			(at 0 0.4445 270)
			(size 0.1397 0.1397)
			(layers "F.Cu" "F.Mask" "F.Paste")
			(net "EXP_SCL_0")
			(options
				(clearance outline)
				(anchor circle)
			)
			(primitives
				(gr_poly
					(pts
						(arc
							(start -0.1778 -0.2794)
							(mid -0.249642 -0.249642)
							(end -0.2794 -0.1778)
						)
						(arc
							(start -0.2794 0.1778)
							(mid -0.249642 0.249642)
							(end -0.1778 0.2794)
						)
						(arc
							(start 0.1778 0.2794)
							(mid 0.249642 0.249642)
							(end 0.2794 0.1778)
						)
						(arc
							(start 0.2794 -0.1778)
							(mid 0.249642 -0.249642)
							(end 0.1778 -0.2794)
						)
					)
					(width 0)
					(fill yes)
				)
			)
		)
	)
	(footprint ""
		(layer "F.Cu")
		(at 221.361 -102.743 -90)
		(property "Reference" "PR125"
			(at 0 0 270)
			(layer "F.SilkS")
			(hide yes)
			(effects
				(font
					(size 1.27 1.27)
				)
			)
		)
		(property "Value" "2K7R2J-GP"
			(at 0.064008 -3.993896 270)
			(unlocked yes)
			(layer "F.Fab")
			(hide yes)
			(effects
				(font
					(size 1.016 1.016)
					(thickness 0.1524)
				)
			)
		)
		(property "Device Type" "R402H16"
			(at 0.064008 -5.517896 270)
			(unlocked yes)
			(layer "F.Fab")
			(hide yes)
			(effects
				(font
					(size 1.016 1.016)
					(thickness 0.1524)
				)
			)
		)
		(duplicate_pad_numbers_are_jumpers no)
		(fp_line
			(start -0.508 -0.9398)
			(end -0.508 0.9398)
			(stroke
				(width 0.1524)
				(type default)
			)
			(layer "F.SilkS")
		)
		(fp_line
			(start 0.508 -0.9398)
			(end -0.508 -0.9398)
			(stroke
				(width 0.1524)
				(type default)
			)
			(layer "F.SilkS")
		)
		(fp_rect
			(start -0.508 0.9398)
			(end 0.508 -0.9398)
			(stroke
				(width 0)
				(type default)
			)
			(fill no)
			(layer "F.CrtYd")
		)
		(fp_rect
			(start -0.508 0.9398)
			(end 0.508 -0.9398)
			(stroke
				(width 0)
				(type default)
			)
			(fill no)
			(layer "F.Fab")
		)
		(pad "1" smd custom
			(at 0 -0.4445 270)
			(size 0.1397 0.1397)
			(layers "F.Cu" "F.Mask" "F.Paste")
			(net "P3V3_STBY")
			(options
				(clearance outline)
				(anchor circle)
			)
			(primitives
				(gr_poly
					(pts
						(arc
							(start -0.1778 -0.2794)
							(mid -0.249642 -0.249642)
							(end -0.2794 -0.1778)
						)
						(arc
							(start -0.2794 0.1778)
							(mid -0.249642 0.249642)
							(end -0.1778 0.2794)
						)
						(arc
							(start 0.1778 0.2794)
							(mid 0.249642 0.249642)
							(end 0.2794 0.1778)
						)
						(arc
							(start 0.2794 -0.1778)
							(mid 0.249642 -0.249642)
							(end 0.1778 -0.2794)
						)
					)
					(width 0)
					(fill yes)
				)
			)
		)
		(pad "2" smd custom
			(at 0 0.4445 270)
			(size 0.1397 0.1397)
			(layers "F.Cu" "F.Mask" "F.Paste")
			(net "PWRGD_P1V5_C_PG")
			(options
				(clearance outline)
				(anchor circle)
			)
			(primitives
				(gr_poly
					(pts
						(arc
							(start -0.1778 -0.2794)
							(mid -0.249642 -0.249642)
							(end -0.2794 -0.1778)
						)
						(arc
							(start -0.2794 0.1778)
							(mid -0.249642 0.249642)
							(end -0.1778 0.2794)
						)
						(arc
							(start 0.1778 0.2794)
							(mid 0.249642 0.249642)
							(end 0.2794 0.1778)
						)
						(arc
							(start 0.2794 -0.1778)
							(mid 0.249642 -0.249642)
							(end 0.1778 -0.2794)
						)
					)
					(width 0)
					(fill yes)
				)
			)
		)
	)
	(footprint ""
		(layer "F.Cu")
		(at 258.318 -136.779)
		(property "Reference" "R7903"
			(at 0 0 0)
			(layer "F.SilkS")
			(hide yes)
			(effects
				(font
					(size 1.27 1.27)
				)
			)
		)
		(property "Value" "0R2J-2-GP"
			(at 0.064008 -3.993896 0)
			(unlocked yes)
			(layer "F.Fab")
			(hide yes)
			(effects
				(font
					(size 1.016 1.016)
					(thickness 0.1524)
				)
			)
		)
		(property "Device Type" "R402H16"
			(at 0.064008 -5.517896 0)
			(unlocked yes)
			(layer "F.Fab")
			(hide yes)
			(effects
				(font
					(size 1.016 1.016)
					(thickness 0.1524)
				)
			)
		)
		(duplicate_pad_numbers_are_jumpers no)
		(fp_line
			(start -0.508 -0.9398)
			(end -0.508 0.9398)
			(stroke
				(width 0.1524)
				(type default)
			)
			(layer "F.SilkS")
		)
		(fp_line
			(start 0.508 -0.9398)
			(end -0.508 -0.9398)
			(stroke
				(width 0.1524)
				(type default)
			)
			(layer "F.SilkS")
		)
		(fp_rect
			(start -0.508 0.9398)
			(end 0.508 -0.9398)
			(stroke
				(width 0)
				(type default)
			)
			(fill no)
			(layer "F.CrtYd")
		)
		(fp_rect
			(start -0.508 0.9398)
			(end 0.508 -0.9398)
			(stroke
				(width 0)
				(type default)
			)
			(fill no)
			(layer "F.Fab")
		)
		(pad "1" smd custom
			(at 0 -0.4445)
			(size 0.1397 0.1397)
			(layers "F.Cu" "F.Mask" "F.Paste")
			(net "CPU_S_RXD")
			(options
				(clearance outline)
				(anchor circle)
			)
			(primitives
				(gr_poly
					(pts
						(arc
							(start -0.1778 -0.2794)
							(mid -0.249642 -0.249642)
							(end -0.2794 -0.1778)
						)
						(arc
							(start -0.2794 0.1778)
							(mid -0.249642 0.249642)
							(end -0.1778 0.2794)
						)
						(arc
							(start 0.1778 0.2794)
							(mid 0.249642 0.249642)
							(end 0.2794 0.1778)
						)
						(arc
							(start 0.2794 -0.1778)
							(mid 0.249642 -0.249642)
							(end 0.1778 -0.2794)
						)
					)
					(width 0)
					(fill yes)
				)
			)
		)
		(pad "2" smd custom
			(at 0 0.4445)
			(size 0.1397 0.1397)
			(layers "F.Cu" "F.Mask" "F.Paste")
			(net "CPU_U192_PIN5_RX")
			(options
				(clearance outline)
				(anchor circle)
			)
			(primitives
				(gr_poly
					(pts
						(arc
							(start -0.1778 -0.2794)
							(mid -0.249642 -0.249642)
							(end -0.2794 -0.1778)
						)
						(arc
							(start -0.2794 0.1778)
							(mid -0.249642 0.249642)
							(end -0.1778 0.2794)
						)
						(arc
							(start 0.1778 0.2794)
							(mid 0.249642 0.249642)
							(end 0.2794 0.1778)
						)
						(arc
							(start 0.2794 -0.1778)
							(mid 0.249642 -0.249642)
							(end 0.1778 -0.2794)
						)
					)
					(width 0)
					(fill yes)
				)
			)
		)
	)
	(footprint ""
		(layer "F.Cu")
		(at 131.318 -88.519 90)
		(property "Reference" "SC1264"
			(at 0 0 90)
			(layer "F.SilkS")
			(hide yes)
			(effects
				(font
					(size 1.27 1.27)
				)
			)
		)
		(property "Value" "SCD01U10V1KX-GP"
			(at -2.8321 -1.7399 90)
			(unlocked yes)
			(layer "F.Fab")
			(hide yes)
			(effects
				(font
					(size 1.016 1.016)
					(thickness 0.1524)
				)
			)
		)
		(property "Device Type" "C0201H13"
			(at -2.8321 -3.2639 90)
			(unlocked yes)
			(layer "F.Fab")
			(hide yes)
			(effects
				(font
					(size 1.016 1.016)
					(thickness 0.1524)
				)
			)
		)
		(duplicate_pad_numbers_are_jumpers no)
		(fp_rect
			(start -0.2794 0.6477)
			(end 0.2794 -0.6477)
			(stroke
				(width 0)
				(type default)
			)
			(fill no)
			(layer "F.CrtYd")
		)
		(fp_rect
			(start -0.2794 0.6477)
			(end 0.2794 -0.6477)
			(stroke
				(width 0)
				(type default)
			)
			(fill no)
			(layer "F.Fab")
		)
		(pad "1" smd custom
			(at 0 -0.2794 90)
			(size 0.0762 0.0762)
			(layers "F.Cu" "F.Mask" "F.Paste")
			(net "3X24_SAS_TX17_P")
			(options
				(clearance outline)
				(anchor circle)
			)
			(primitives
				(gr_poly
					(pts
						(arc
							(start 0.1524 -0.127)
							(mid 0.137521 -0.162921)
							(end 0.1016 -0.1778)
						)
						(arc
							(start -0.1016 -0.1778)
							(mid -0.137521 -0.162921)
							(end -0.1524 -0.127)
						)
						(arc
							(start -0.1524 0.127)
							(mid -0.137521 0.162921)
							(end -0.1016 0.1778)
						)
						(arc
							(start 0.1016 0.1778)
							(mid 0.137521 0.162921)
							(end 0.1524 0.127)
						)
					)
					(width 0)
					(fill yes)
				)
			)
		)
		(pad "2" smd custom
			(at 0 0.2794 90)
			(size 0.0762 0.0762)
			(layers "F.Cu" "F.Mask" "F.Paste")
			(net "SAS_EXP2CONN_TX_P_21")
			(options
				(clearance outline)
				(anchor circle)
			)
			(primitives
				(gr_poly
					(pts
						(arc
							(start 0.1524 -0.127)
							(mid 0.137521 -0.162921)
							(end 0.1016 -0.1778)
						)
						(arc
							(start -0.1016 -0.1778)
							(mid -0.137521 -0.162921)
							(end -0.1524 -0.127)
						)
						(arc
							(start -0.1524 0.127)
							(mid -0.137521 0.162921)
							(end -0.1016 0.1778)
						)
						(arc
							(start 0.1016 0.1778)
							(mid 0.137521 0.162921)
							(end 0.1524 0.127)
						)
					)
					(width 0)
					(fill yes)
				)
			)
		)
	)
	(footprint ""
		(layer "F.Cu")
		(at 208.153 -215.773 -90)
		(property "Reference" "C43"
			(at 0 0 270)
			(layer "F.SilkS")
			(hide yes)
			(effects
				(font
					(size 1.27 1.27)
				)
			)
		)
		(property "Value" "SCD1U16V2KX-3GP"
			(at 1.1811 -2.7051 270)
			(unlocked yes)
			(layer "F.Fab")
			(hide yes)
			(effects
				(font
					(size 1.016 1.016)
					(thickness 0.1524)
				)
			)
		)
		(property "Device Type" "C402H22"
			(at 1.1811 -4.2291 270)
			(unlocked yes)
			(layer "F.Fab")
			(hide yes)
			(effects
				(font
					(size 1.016 1.016)
					(thickness 0.1524)
				)
			)
		)
		(duplicate_pad_numbers_are_jumpers no)
		(fp_rect
			(start -0.4318 0.9525)
			(end 0.4318 -0.9525)
			(stroke
				(width 0)
				(type default)
			)
			(fill no)
			(layer "F.CrtYd")
		)
		(fp_rect
			(start -0.4318 0.9525)
			(end 0.4318 -0.9525)
			(stroke
				(width 0)
				(type default)
			)
			(fill no)
			(layer "F.Fab")
		)
		(pad "1" smd custom
			(at 0 -0.4445 270)
			(size 0.1524 0.1524)
			(layers "F.Cu" "F.Mask" "F.Paste")
			(net "P3V3_STBY")
			(options
				(clearance outline)
				(anchor circle)
			)
			(primitives
				(gr_poly
					(pts
						(arc
							(start 0.3048 -0.2032)
							(mid 0.275042 -0.275042)
							(end 0.2032 -0.3048)
						)
						(arc
							(start -0.2032 -0.3048)
							(mid -0.275042 -0.275042)
							(end -0.3048 -0.2032)
						)
						(arc
							(start -0.3048 0.2032)
							(mid -0.275042 0.275042)
							(end -0.2032 0.3048)
						)
						(arc
							(start 0.2032 0.3048)
							(mid 0.275042 0.275042)
							(end 0.3048 0.2032)
						)
					)
					(width 0)
					(fill yes)
				)
			)
		)
		(pad "2" smd custom
			(at 0 0.4445 270)
			(size 0.1524 0.1524)
			(layers "F.Cu" "F.Mask" "F.Paste")
			(net "GND")
			(options
				(clearance outline)
				(anchor circle)
			)
			(primitives
				(gr_poly
					(pts
						(arc
							(start 0.3048 -0.2032)
							(mid 0.275042 -0.275042)
							(end 0.2032 -0.3048)
						)
						(arc
							(start -0.2032 -0.3048)
							(mid -0.275042 -0.275042)
							(end -0.3048 -0.2032)
						)
						(arc
							(start -0.3048 0.2032)
							(mid -0.275042 0.275042)
							(end -0.2032 0.3048)
						)
						(arc
							(start 0.2032 0.3048)
							(mid 0.275042 0.275042)
							(end 0.3048 0.2032)
						)
					)
					(width 0)
					(fill yes)
				)
			)
		)
	)
	(footprint ""
		(layer "F.Cu")
		(at 260.023864 -231.004872 180)
		(property "Reference" "PC102"
			(at 0 0 180)
			(layer "F.SilkS")
			(hide yes)
			(effects
				(font
					(size 1.27 1.27)
				)
			)
		)
		(property "Value" "SCD1U16V2KX-3GP"
			(at 1.1811 -2.7051 180)
			(unlocked yes)
			(layer "F.Fab")
			(hide yes)
			(effects
				(font
					(size 1.016 1.016)
					(thickness 0.1524)
				)
			)
		)
		(property "Device Type" "C402H22"
			(at 1.1811 -4.2291 180)
			(unlocked yes)
			(layer "F.Fab")
			(hide yes)
			(effects
				(font
					(size 1.016 1.016)
					(thickness 0.1524)
				)
			)
		)
		(duplicate_pad_numbers_are_jumpers no)
		(fp_rect
			(start -0.4318 0.9525)
			(end 0.4318 -0.9525)
			(stroke
				(width 0)
				(type default)
			)
			(fill no)
			(layer "F.CrtYd")
		)
		(fp_rect
			(start -0.4318 0.9525)
			(end 0.4318 -0.9525)
			(stroke
				(width 0)
				(type default)
			)
			(fill no)
			(layer "F.Fab")
		)
		(pad "1" smd custom
			(at 0 -0.4445 180)
			(size 0.1524 0.1524)
			(layers "F.Cu" "F.Mask" "F.Paste")
			(net "TPS74801_1V26_STBY_BIAS")
			(options
				(clearance outline)
				(anchor circle)
			)
			(primitives
				(gr_poly
					(pts
						(arc
							(start 0.3048 -0.2032)
							(mid 0.275042 -0.275042)
							(end 0.2032 -0.3048)
						)
						(arc
							(start -0.2032 -0.3048)
							(mid -0.275042 -0.275042)
							(end -0.3048 -0.2032)
						)
						(arc
							(start -0.3048 0.2032)
							(mid -0.275042 0.275042)
							(end -0.2032 0.3048)
						)
						(arc
							(start 0.2032 0.3048)
							(mid 0.275042 0.275042)
							(end 0.3048 0.2032)
						)
					)
					(width 0)
					(fill yes)
				)
			)
		)
		(pad "2" smd custom
			(at 0 0.4445 180)
			(size 0.1524 0.1524)
			(layers "F.Cu" "F.Mask" "F.Paste")
			(net "GND")
			(options
				(clearance outline)
				(anchor circle)
			)
			(primitives
				(gr_poly
					(pts
						(arc
							(start 0.3048 -0.2032)
							(mid 0.275042 -0.275042)
							(end 0.2032 -0.3048)
						)
						(arc
							(start -0.2032 -0.3048)
							(mid -0.275042 -0.275042)
							(end -0.3048 -0.2032)
						)
						(arc
							(start -0.3048 0.2032)
							(mid -0.275042 0.275042)
							(end -0.2032 0.3048)
						)
						(arc
							(start 0.2032 0.3048)
							(mid 0.275042 0.275042)
							(end 0.3048 0.2032)
						)
					)
					(width 0)
					(fill yes)
				)
			)
		)
	)
	(footprint ""
		(layer "F.Cu")
		(at 112.30737 -77.724)
		(property "Reference" "STP75"
			(at 0 0 0)
			(layer "F.SilkS")
			(hide yes)
			(effects
				(font
					(size 1.27 1.27)
				)
			)
		)
		(property "Value" "TPAD28"
			(at 0.0127 -1.8034 0)
			(unlocked yes)
			(layer "F.Fab")
			(hide yes)
			(effects
				(font
					(size 1.016 1.016)
					(thickness 0.1524)
				)
			)
		)
		(property "Device Type" "TPAD28"
			(at 0.0127 -3.3274 0)
			(unlocked yes)
			(layer "F.Fab")
			(hide yes)
			(effects
				(font
					(size 1.016 1.016)
					(thickness 0.1524)
				)
			)
		)
		(duplicate_pad_numbers_are_jumpers no)
		(fp_poly
			(pts
				(arc
					(start 0.3556 0)
					(mid -0.3556 0)
					(end 0.3556 0)
				)
			)
			(stroke
				(width 0)
				(type default)
			)
			(fill no)
			(layer "F.CrtYd")
		)
		(fp_poly
			(pts
				(arc
					(start 0.6096 0)
					(mid -0.6096 0)
					(end 0.6096 0)
				)
			)
			(stroke
				(width 0)
				(type default)
			)
			(fill no)
			(layer "F.Fab")
		)
		(pad "1" smd circle
			(at 0 0)
			(size 0.7112 0.7112)
			(layers "F.Cu" "F.Mask" "F.Paste")
			(net "EXP_TEST_MUX35")
		)
	)
	(footprint ""
		(layer "F.Cu")
		(at 191.697864 -29.663136 90)
		(property "Reference" "R394"
			(at 0 0 90)
			(layer "F.SilkS")
			(hide yes)
			(effects
				(font
					(size 1.27 1.27)
				)
			)
		)
		(property "Value" "4K75R2F-1-GP"
			(at 0.064008 -3.993896 90)
			(unlocked yes)
			(layer "F.Fab")
			(hide yes)
			(effects
				(font
					(size 1.016 1.016)
					(thickness 0.1524)
				)
			)
		)
		(property "Device Type" "R402H16"
			(at 0.064008 -5.517896 90)
			(unlocked yes)
			(layer "F.Fab")
			(hide yes)
			(effects
				(font
					(size 1.016 1.016)
					(thickness 0.1524)
				)
			)
		)
		(duplicate_pad_numbers_are_jumpers no)
		(fp_line
			(start 0.508 -0.9398)
			(end -0.508 -0.9398)
			(stroke
				(width 0.1524)
				(type default)
			)
			(layer "F.SilkS")
		)
		(fp_line
			(start -0.508 -0.9398)
			(end -0.508 0.9398)
			(stroke
				(width 0.1524)
				(type default)
			)
			(layer "F.SilkS")
		)
		(fp_rect
			(start -0.508 0.9398)
			(end 0.508 -0.9398)
			(stroke
				(width 0)
				(type default)
			)
			(fill no)
			(layer "F.CrtYd")
		)
		(fp_rect
			(start -0.508 0.9398)
			(end 0.508 -0.9398)
			(stroke
				(width 0)
				(type default)
			)
			(fill no)
			(layer "F.Fab")
		)
		(pad "1" smd custom
			(at 0 -0.4445 90)
			(size 0.1397 0.1397)
			(layers "F.Cu" "F.Mask" "F.Paste")
			(net "PHY_TX_ER_PD")
			(options
				(clearance outline)
				(anchor circle)
			)
			(primitives
				(gr_poly
					(pts
						(arc
							(start -0.1778 -0.2794)
							(mid -0.249642 -0.249642)
							(end -0.2794 -0.1778)
						)
						(arc
							(start -0.2794 0.1778)
							(mid -0.249642 0.249642)
							(end -0.1778 0.2794)
						)
						(arc
							(start 0.1778 0.2794)
							(mid 0.249642 0.249642)
							(end 0.2794 0.1778)
						)
						(arc
							(start 0.2794 -0.1778)
							(mid 0.249642 -0.249642)
							(end 0.1778 -0.2794)
						)
					)
					(width 0)
					(fill yes)
				)
			)
		)
		(pad "2" smd custom
			(at 0 0.4445 90)
			(size 0.1397 0.1397)
			(layers "F.Cu" "F.Mask" "F.Paste")
			(net "GND")
			(options
				(clearance outline)
				(anchor circle)
			)
			(primitives
				(gr_poly
					(pts
						(arc
							(start -0.1778 -0.2794)
							(mid -0.249642 -0.249642)
							(end -0.2794 -0.1778)
						)
						(arc
							(start -0.2794 0.1778)
							(mid -0.249642 0.249642)
							(end -0.1778 0.2794)
						)
						(arc
							(start 0.1778 0.2794)
							(mid 0.249642 0.249642)
							(end 0.2794 0.1778)
						)
						(arc
							(start 0.2794 -0.1778)
							(mid 0.249642 -0.249642)
							(end 0.1778 -0.2794)
						)
					)
					(width 0)
					(fill yes)
				)
			)
		)
	)
)
